FILE_TYPE = CONNECTIVITY;
{Allegro Design Entry HDL 17.2-2016 S081 (4005846) 1/11/2022}
"PAGE_NUMBER" = 81;
0"NC";
1"CPU0_CORETYPE1";
2"FM_SMB_RST_E1S_4_N";
3"FM_CPU0_SP5R2";
4"FM_CPU0_SP5R1";
5"FM_CPU1_CORETYPE0";
6"PVDD11_S3_P0_PMALERT";
7"PRSNT_SLOT3_R_N";
8"SLOT1_SKU_ID0";
9"FM_SMB_RST_E1S_3_N";
10"CPU1_SP5R2";
11"CPU1_SP5R1";
12"PRSNT_N_E1S_3_R";
13"CPU1_CORETYPE1";
14"FM_CPU0_CORETYPE1";
15"FM_CPU1_CORETYPE1";
16"PRSNT_N_E1S_4_R";
17"FM_PVDDCR_CPU1_P0_EN";
18"CPU0_SP5R3";
19"PWRGD_PVDDCR_CPU1_P0";
20"PWRGD_CHAF_CPU1";
21"FM_PVDDCR_CPU1_P0_R_EN";
22"FM_CPU1_SP5R2";
23"FM_CPU1_SP5R1";
24"CPU1_CORETYPE2";
25"CPU0_SP5R2";
26"PVDD11_S3_P1_PMALERT";
27"PMDU_NODE_ID5";
28"FM_CPU0_SP5R4";
29"FM_PRSNT_CPU0_R_N";
30"PRSNT_N_E1S_2_R";
31"FM_PLD_OCP_AUX_PWR_R_EN";
32"PVDDCR_CPU0_P1_PMALERT";
33"FM_CLKREQ_M2_1_N";
34"PWRGD_NIC_PWR_GOOD";
35"CLR_CMOS";
36"FM_CLKREQ_M2_2_N";
37"FM_PLD_OCP_AUX_PWR_EN";
38"PRSNT_N_E1S_1_R";
39"FM_SMB_RST_E1S_2_N";
40"CPU0_SP5R4";
41"FM_PRSNT_CPU0_N";
42"FM_SMB_RST_E1S_1_N";
43"PWRGD_CHAF_CPU0";
44"FM_CLR_CMOS";
45"P12V_OCP_PWRGD";
46"PVDDCR_SOC_P0_EN";
47"PMDU_NODE_ID2";
48"PWRGD_CHGL_CPU0";
49"PSU2_PS_ON_N";
50"CPU0_CORETYPE2";
51"CPU0_CORETYPE0";
52"FM_PVDDCR_CPU1_P1_R_EN";
53"FM_PVDD11_S3_P0_EN";
54"PWRGD_PVDDCR_CPU0_P0";
55"PWRGD_PVDDCR_SOC_P0";
56"CPU0_XTRIG_L5";
57"CPU0_FPGA_SPARE_3";
58"CPU0_XTRIG_L7";
59"CPU1_FPGA_SPARE2";
60"PVDDCR_CPU0_P0_OCP_N";
61"PVDDCR_CPU1_P1_OCP_N";
62"FM_PVDDCR_CPU0_P1_OCP_N";
63"FM_CPU1_PROCHOT_R_N";
64"FM_PVDD11_S3_P1_OCP_N";
65"FM_PVDD11_S3_P0_OCP_N";
66"FM_CPU0_FPGA_SPARE_3";
67"FM_PLD_OCP_MAIN_PWR_EN_R";
68"CPU0_SP5R1";
69"CPU1_CORETYPE0";
70"PVDDCR_CPU1_P0_OCP_N";
71"PMDU_NODE_ID4";
72"PMDU_NODE_ID3";
73"PRSNT_SLOT3_N";
74"FM_CPU0_CORETYPE0";
75"FM_CPU0_CORETYPE2";
76"SCM_PRSNT0_N";
77"PMDU_NODE_ID1";
78"PVDDCR_CPU1_P0_SMB_ALERT";
79"PVDDCR_CPU1_P1_SMB_ALERT";
80"SLOT2_SKU_ID0";
81"SLOT1_SKU_ID1";
82"FM_CPU1_CORETYPE2";
83"FM_CPU1_SP5R3";
84"FM_CPU0_SP5R3";
85"CPU1_SP5R3";
86"CPU1_FPGA_SPARE3";
87"CPU1_FPGA_SPARE0";
88"CPU0_FPGA_SPARE_0";
89"CPU1_FPGA_SPARE1";
90"CPU1_SP5R4";
91"CPU1_XTRIG_L7";
92"FM_CPU0_XTRIG_L7";
93"FM_CPU1_FPGA_SPARE1";
94"FM_PWRGD_PVDDCR_CPU1_P0";
95"FM_CPU1_SP5R4";
96"PWRGD_CHGL_CPU1";
97"FM_CPU1_XTRIG_L4";
98"FM_CPU1_XTRIG_L5";
99"CPU0_FPGA_SPARE_1";
100"CPU0_XTRIG_L6";
101"FM_CPU0_FPGA_SPARE_0";
102"FM_PVDDCR_CPU0_P0_OCP_N";
103"FM_PVDDCR_CPU1_P1_OCP_N";
104"FM_PVDDCR_CPU1_P0_OCP_N";
105"FM_CPU1_FPGA_SPARE2";
106"FM_CPU1_FPGA_SPARE3";
107"CPU1_XTRIG_L6";
108"CPU1_XTRIG_L5";
109"CPU1_XTRIG_L4";
110"CPU1_SA1";
111"CPU0_XTRIG_L4";
112"CPU0_FPGA_SPARE_2";
113"FM_CPU0_FPGA_SPARE_1";
114"FM_CPU0_XTRIG_L6";
115"FM_CPU1_SA1";
116"FM_CPU1_XTRIG_L6";
117"FM_CPU1_FPGA_SPARE0";
118"FM_CPU1_XTRIG_L7";
119"FM_CPU0_XTRIG_L5";
120"FM_CPU0_XTRIG_L4";
121"FM_CPU0_FPGA_SPARE_2";
122"FM_CPU0_SA0";
123"CPU0_SA1";
124"PVDD11_S3_P0_OCP_N";
125"GND\g";
126"P3V3_STBY\g"VOLTAGE"3.3"VOLTAGE"3.3"VOLTAGE"3.3"VOLTAGE"3.3"VOLTAGE"3.3"VOLTAGE"3.3";
127"P3V3_STBY\g";
128"P1V8_STBY\g";
129"P3V3_STBY\g";
130"P1V8_STBY\g";
131"FM_CPU0_SA1";
132"FM_CPU0_PROCHOT_R_N";
133"FM_CPU1_SA0";
134"CPU0_THERMTRIP_R_N";
135"CPU1_PROCHOT_N";
136"PVDDCR_CPU0_P1_OCP_N";
137"PVDD11_S3_P1_OCP_N";
138"CPU1_SA0";
139"CPU0_PROCHOT_N";
140"CPU0_SA0";
141"FM_INT_CPU0_HP_UBM_N";
142"FM_PRSNT_CPU1_N";
143"FM_PVDDCR_CPU1_P1_EN";
144"FM_PLD_OCP_MAIN_PWR_EN";
145"PVDD11_S3_P0_EN";
146"SMB_P1V8_M2_1_ALERT_N";
147"CPU1_THERMTRIP_R_N";
148"SMB_P1V8_M2_2_ALERT_N";
149"HPM_BRD_REV_ID0";
150"HPM_BRD_REV_ID1";
151"HPM_BRD_REV_ID2";
152"FM_PRSNT_CPU1_R_N";
153"FM_INT_CPU0_HP_UBM_R_N";
%"VCC_CORE"
"1","(-1525,1950)","0","pure_quanta_power","I666";
;
HDL_POWER"P1V8_STBY"
CDS_LIB"pure_quanta_power";
"A"130;
%"UNIVERSAL_POWER"
"1","(-1550,1225)","2","pure_quanta_power","I667";
;
HDL_POWER"P3V3_STBY"
CDS_LIB"pure_quanta_power";
"A"129;
%"VCC_CORE"
"1","(-3350,1900)","0","pure_quanta_power","I668";
;
HDL_POWER"P1V8_STBY"
CDS_LIB"pure_quanta_power";
"A"128;
%"UNIVERSAL_POWER"
"1","(-3150,2650)","2","pure_quanta_power","I669";
;
HDL_POWER"P3V3_STBY"
CDS_LIB"pure_quanta_power";
"A"127;
%"LCMXO3D9400HC5BG484C"
"5","(-2300,1575)","0","pure_quanta","I670";
;
LOCATION"U18"
$SEC"5"
CDS_SEC"5"
PART_NUMBER"AJ094000T05"
MATERIAL"IC"
VALUE"LCMXO3D-9400HC-5BG484C"
PART_TYPE"SMLF"
CDS_LIB"pure_quanta"
CDS_LMAN_SYM_OUTLINE"-400,1000,400,-1000"
NEEDS_NO_SIZE"TRUE";
"VCCIO0_G13"
$PN"G13"129;
"VCCIO0_H9"
$PN"H9"129;
"VCCIO0_H14"
$PN"H14"129;
"VCCIO0_H12"
$PN"H12"129;
"VCCIO0_H11"
$PN"H11"129;
"VCCIO0_G10"
$PN"G10"129;
"VCCIO0_C16"
$PN"C16"129;
"VCCIO0_C12"
$PN"C12"129;
"VCCIO0_C7"
$PN"C7"129;
"VCCIO1_V20"
$PN"V20"130;
"VCCIO1_P15"
$PN"P15"130;
"VCCIO1_N15"
$PN"N15"130;
"VCCIO1_M18"
$PN"M18"130;
"VCCIO1_M15"
$PN"M15"130;
"VCCIO1_L15"
$PN"L15"130;
"VCCIO1_K15"
$PN"K15"130;
"VCCIO1_J15"
$PN"J15"130;
"VCCIO1_F20"
$PN"F20"130;
"VCCIO2_W16"
$PN"W16"126;
"VCCIO2_W11"
$PN"W11"126;
"VCCIO2_W7"
$PN"W7"126;
"VCCIO2_R14"
$PN"R14"126;
"VCCIO2_R13"
$PN"R13"126;
"VCCIO2_R12"
$PN"R12"126;
"VCCIO2_R11"
$PN"R11"126;
"VCCIO2_R10"
$PN"R10"126;
"VCCIO2_R9"
$PN"R9"126;
"VCCIO3_V3"
$PN"V3"126;
"VCCIO3_P8"
$PN"P8"126;
"VCCIO3_N8"
$PN"N8"126;
"VCCIO4_M3"
$PN"M3"126;
"VCCIO4_M8"
$PN"M8"126;
"VCCIO4_L8"
$PN"L8"126;
"VCCIO5_K8"
$PN"K8"128;
"VCCIO5_J8"
$PN"J8"128;
"VCCIO5_F3"
$PN"F3"128;
"VCC_N13"
$PN"N13"127;
"VCC_N12"
$PN"N12"127;
"VCC_N11"
$PN"N11"127;
"VCC_N10"
$PN"N10"127;
"VCC_M12"
$PN"M12"127;
"VCC_M11"
$PN"M11"127;
"VCC_L12"
$PN"L12"127;
"VCC_L11"
$PN"L11"127;
"VCC_K13"
$PN"K13"127;
"VCC_K12"
$PN"K12"127;
"VCC_K11"
$PN"K11"127;
"VCC_K10"
$PN"K10"127;
%"UNIVERSAL_POWER"
"1","(-3650,1750)","2","pure_quanta_power","I671";
;
HDL_POWER"P3V3_STBY"
CDS_LIB"pure_quanta_power";
"A"126;
%"Q_RES"
"1","(-3225,6075)","0","pure_quanta","I696";
;
LOCATION"R278"
$SEC"1"
CDS_SEC"1"
VALUE"0"
ROOM"RST_CPU0_PLD_TO_DIMM"
PACK_TYPE"0402LF"
PART_NUMBER"CS00002JB38"
TOLERANCE"5%"
MATERIAL"CHIP"
WATTAGE"1/16W"
BOM_COST"MEM"
CDS_LIB"pure_quanta";
"B"
$PN"2"137;
"A"
$PN"1"64;
%"Q_RES"
"1","(-3225,6125)","0","pure_quanta","I697";
;
LOCATION"R270"
$SEC"1"
CDS_SEC"1"
VALUE"33"
ROOM"RST_CPU0_PLD_TO_DIMM"
PACK_TYPE"0402LF"
PART_NUMBER"CS03302JB29"
TOLERANCE"5%"
MATERIAL"CHIP"
WATTAGE"1/16W"
CDS_LIB"pure_quanta"
BOM_COST"MEM";
"B"
$PN"2"135;
"A"
$PN"1"63;
%"Q_RES"
"1","(-3225,6175)","0","pure_quanta","I698";
;
LOCATION"R284"
$SEC"1"
CDS_SEC"1"
VALUE"0"
ROOM"RST_CPU0_PLD_TO_DIMM"
PACK_TYPE"0402LF"
PART_NUMBER"CS00002JB38"
TOLERANCE"5%"
MATERIAL"CHIP"
WATTAGE"1/16W"
CDS_LIB"pure_quanta"
BOM_COST"MEM";
"B"
$PN"2"136;
"A"
$PN"1"62;
%"Q_RES"
"1","(-3225,6025)","0","pure_quanta","I699";
;
LOCATION"R226"
$SEC"1"
CDS_SEC"1"
VALUE"0"
ROOM"RST_CPU0_PLD_TO_DIMM"
PACK_TYPE"0402LF"
PART_NUMBER"CS00002JB38"
TOLERANCE"5%"
MATERIAL"CHIP"
WATTAGE"1/16W"
BOM_COST"MEM"
CDS_LIB"pure_quanta";
"B"
$PN"2"124;
"A"
$PN"1"65;
%"Q_RES"
"1","(-3225,5825)","0","pure_quanta","I700";
;
LOCATION"R179"
$SEC"1"
CDS_SEC"1"
VALUE"33"
ROOM"RST_CPU0_PLD_TO_DIMM"
PACK_TYPE"0402LF"
PART_NUMBER"CS03302JB29"
TOLERANCE"5%"
MATERIAL"CHIP"
WATTAGE"1/16W"
CDS_LIB"pure_quanta"
BOM_COST"MEM";
"B"
$PN"2"139;
"A"
$PN"1"132;
%"Q_RES"
"1","(-3225,5625)","0","pure_quanta","I701";
;
LOCATION"R81"
$SEC"1"
CDS_SEC"1"
VALUE"33"
ROOM"RST_CPU0_PLD_TO_DIMM"
PACK_TYPE"0402LF"
PART_NUMBER"CS03302JB29"
TOLERANCE"5%"
MATERIAL"CHIP"
WATTAGE"1/16W"
BOM_COST"MEM"
CDS_LIB"pure_quanta";
"B"
$PN"2"141;
"A"
$PN"1"153;
%"Q_RES"
"1","(-3175,5075)","0","pure_quanta","I702";
;
LOCATION"R271"
$SEC"1"
CDS_SEC"1"
VALUE"0"
ROOM"RST_CPU0_PLD_TO_DIMM"
PACK_TYPE"0402LF"
PART_NUMBER"CS00002JB38"
TOLERANCE"5%"
MATERIAL"CHIP"
WATTAGE"1/16W"
CDS_LIB"pure_quanta"
BOM_COST"MEM";
"B"
$PN"2"142;
"A"
$PN"1"152;
%"Q_RES"
"1","(-3175,5025)","0","pure_quanta","I703";
;
LOCATION"R227"
$SEC"1"
CDS_SEC"1"
VALUE"33"
ROOM"RST_CPU0_PLD_TO_DIMM"
PACK_TYPE"0402LF"
PART_NUMBER"CS03302JB29"
TOLERANCE"5%"
MATERIAL"CHIP"
WATTAGE"1/16W"
CDS_LIB"pure_quanta"
BOM_COST"MEM";
"B"
$PN"2"145;
"A"
$PN"1"53;
%"Q_RES"
"1","(-3175,5125)","0","pure_quanta","I704";
;
LOCATION"R285"
$SEC"1"
CDS_SEC"1"
VALUE"33"
ROOM"RST_CPU0_PLD_TO_DIMM"
PACK_TYPE"0402LF"
PART_NUMBER"CS03302JB29"
TOLERANCE"5%"
MATERIAL"CHIP"
WATTAGE"1/16W"
BOM_COST"MEM"
CDS_LIB"pure_quanta";
"B"
$PN"2"143;
"A"
$PN"1"52;
%"Q_RES"
"1","(-3175,4425)","0","pure_quanta","I730";
;
LOCATION"R182"
$SEC"1"
CDS_SEC"1"
VALUE"0"
ROOM"RST_CPU0_PLD_TO_DIMM"
PACK_TYPE"0402LF"
PART_NUMBER"CS00002JB38"
TOLERANCE"5%"
MATERIAL"CHIP"
WATTAGE"1/16W"
CDS_LIB"pure_quanta"
BOM_COST"MEM";
"B"
$PN"2"41;
"A"
$PN"1"29;
%"Q_RES"
"1","(-3175,4375)","0","pure_quanta","I731";
;
LOCATION"R223"
$SEC"1"
CDS_SEC"1"
VALUE"0"
ROOM"RST_CPU0_PLD_TO_DIMM"
PACK_TYPE"0402LF"
PART_NUMBER"CS00002JB38"
TOLERANCE"5%"
MATERIAL"CHIP"
WATTAGE"1/16W"
BOM_COST"MEM"
CDS_LIB"pure_quanta";
"B"
$PN"2"40;
"A"
$PN"1"28;
%"Q_RES"
"1","(-3225,3975)","2","pure_quanta","I732";
;
LOCATION"R958"
$SEC"1"
CDS_SEC"1"
VALUE"33"
ROOM"RST_CPU0_PLD_TO_DIMM"
PACK_TYPE"0402LF"
PART_NUMBER"CS03302JB29"
TOLERANCE"5%"
MATERIAL"CHIP"
WATTAGE"1/16W"
CDS_LIB"pure_quanta"
BOM_COST"MEM";
"B"
$PN"2"31;
"A"
$PN"1"37;
%"Q_RES"
"1","(-3225,3775)","2","pure_quanta","I733";
;
LOCATION"R275"
$SEC"1"
CDS_SEC"1"
VALUE"33"
ROOM"RST_CPU0_PLD_TO_DIMM"
PACK_TYPE"0402LF"
PART_NUMBER"CS03302JB29"
TOLERANCE"5%"
MATERIAL"CHIP"
WATTAGE"1/16W"
CDS_LIB"pure_quanta"
BOM_COST"MEM";
"B"
$PN"2"44;
"A"
$PN"1"35;
%"Q_RES"
"1","(-3225,3625)","2","pure_quanta","I734";
;
LOCATION"R183"
$SEC"1"
CDS_SEC"1"
VALUE"0"
ROOM"RST_CPU0_PLD_TO_DIMM"
PACK_TYPE"0402LF"
PART_NUMBER"CS00002JB38"
TOLERANCE"5%"
MATERIAL"CHIP"
WATTAGE"1/16W"
CDS_LIB"pure_quanta"
BOM_COST"MEM";
"B"
$PN"2"74;
"A"
$PN"1"51;
%"Q_RES"
"1","(-3225,3575)","2","pure_quanta","I735";
;
LOCATION"R185"
$SEC"1"
CDS_SEC"1"
VALUE"0"
ROOM"RST_CPU0_PLD_TO_DIMM"
PACK_TYPE"0402LF"
PART_NUMBER"CS00002JB38"
TOLERANCE"5%"
MATERIAL"CHIP"
WATTAGE"1/16W"
CDS_LIB"pure_quanta"
BOM_COST"MEM";
"B"
$PN"2"75;
"A"
$PN"1"50;
%"Q_RES"
"1","(-3225,3525)","2","pure_quanta","I736";
;
LOCATION"R959"
$SEC"1"
CDS_SEC"1"
VALUE"33"
ROOM"RST_CPU0_PLD_TO_DIMM"
PACK_TYPE"0402LF"
PART_NUMBER"CS03302JB29"
TOLERANCE"5%"
MATERIAL"CHIP"
WATTAGE"1/16W"
CDS_LIB"pure_quanta"
BOM_COST"MEM";
"B"
$PN"2"67;
"A"
$PN"1"144;
%"LCMXO3D9400HC5BG484C"
"1","(-4825,4825)","0","pure_quanta","I737";
;
LOCATION"U18"
$SEC"1"
CDS_SEC"1"
PART_TYPE"SMLF"
VALUE"LCMXO3D-9400HC-5BG484C"
PART_NUMBER"AJ094000T05"
MATERIAL"IC"
NEEDS_NO_SIZE"TRUE"
CDS_LMAN_SYM_OUTLINE"-500,1400,500,-1400"
CDS_LIB"pure_quanta";
"PL12D"
$PN"K6"151;
"PL12C"
$PN"K7"150;
"PL12B"
$PN"J1"149;
"PL12A"
$PN"J2"131;
"PL11D"
$PN"J3"153;
"PL11C"
$PN"J4"148;
"PL11B"
$PN"J5"147;
"PL11A"
$PN"H5"122;
"PL10D"
$PN"J6"132;
"PL10C"
$PN"J7"133;
"PL10B"
$PN"H1"146;
"PL10A"
$PN"H2"134;
"PL7D"
$PN"H3"65;
"PL7C"
$PN"H4"64;
"PL7B||PCLKC5_0"
$PN"G1"63;
"PL7A||PCLKT5_0"
$PN"G2"62;
"PL30D"
$PN"T7"52;
"PL30C"
$PN"V5"152;
"PL30B||I3C"
$PN"W4"53;
"PL30A||I3C"
$PN"Y3"54;
"PL29D"
$PN"Y2"55;
"PL29C"
$PN"W3"46;
"PL29B||I3C"
$PN"AA1"47;
"PL29A||I3C"
$PN"Y1"48;
"PL28D"
$PN"U5"49;
"PL28C"
$PN"V4"30;
"PL28B"
$PN"W2"45;
"PL28A"
$PN"W1"43;
"PL27D"
$PN"U4"39;
"PL27C"
$PN"U3"38;
"PL27B||PCLKC3_0||I3C"
$PN"V1"29;
"PL27A||PCLKT3_0||I3C"
$PN"U2"28;
"PL19D"
$PN"M7"67;
"PL19C"
$PN"P3"75;
"PL19B"
$PN"R1"74;
"PL19A"
$PN"P2"42;
"PL18D"
$PN"N4"34;
"PL18C"
$PN"N3"44;
"PL18B"
$PN"P1"36;
"PL18A"
$PN"N2"33;
"PL17D"
$PN"M5"32;
"PL17C"
$PN"M6"31;
"PL17B"
$PN"N1"26;
"PL17A"
$PN"M1"27;
"PL26B"
$PN"T4"95;
"PL26A"
$PN"T3"83;
"PL25D"
$PN"R7"94;
"PL25C"
$PN"R6"20;
"PL24D"
$PN"P7"21;
"PL24C"
$PN"R5"9;
"PL24B"
$PN"R4"22;
"PL24A"
$PN"R3"23;
"PL25B||I3C"
$PN"U1"84;
"PL25A||I3C"
$PN"T2"82;
"PL6B"
$PN"F1"102;
"PL6A"
$PN"E1"105;
"PL6D"
$PN"G4"103;
"PL6C"
$PN"G3"104;
"PL16D"
$PN"L4"71;
"PL16C"
$PN"L3"72;
"PL14D"
$PN"L5"78;
"PL14C"
$PN"L6"79;
"PL26D"
$PN"T6"96;
"PL26C"
$PN"T5"0;
"PL21D"
$PN"P6"16;
"PL21C"
$PN"P5"12;
"PL21B"
$PN"T1"15;
"PL21A"
$PN"R2"14;
"PL20D"
$PN"N7"2;
"PL20C"
$PN"N6"3;
"PL20B"
$PN"N5"4;
"PL20A"
$PN"P4"5;
"PL16B||PCLKC4_0"
$PN"M2"76;
"PL16A||PCLKT4_0"
$PN"L1"77;
"PL14B"
$PN"K1"80;
"PL14A"
$PN"K2"81;
"PL13D"
$PN"K3"0;
"PL13C"
$PN"K4"8;
"PL13B"
$PN"K5"7;
"PL13A"
$PN"L7"6;
"PL5D"
$PN"F4"93;
"PL5C"
$PN"E3"92;
"PL5B"
$PN"E2"106;
"PL5A"
$PN"D1"101;
"PL4D"
$PN"H6"66;
"PL4C"
$PN"G5"121;
"PL4B||L_GPLLC_IN"
$PN"D2"120;
"PL4A||L_GPLLT_IN"
$PN"C1"119;
"PL3D"
$PN"H7"117;
"PL3C"
$PN"G6"118;
"PL3B||L_GPLLC_FB"
$PN"F5"113;
"PL3A||L_GPLLT_FB"
$PN"E4"114;
"PL2D"
$PN"G7"115;
"PL2C"
$PN"F6"116;
"PL2B"
$PN"D4"98;
"PL2A"
$PN"D3"97;
%"Q_RES"
"1","(-6425,6075)","0","pure_quanta","I738";
;
LOCATION"R234"
$SEC"1"
CDS_SEC"1"
VALUE"0"
ROOM"RST_CPU0_PLD_TO_DIMM"
PACK_TYPE"0402LF"
PART_NUMBER"CS00002JB38"
TOLERANCE"5%"
MATERIAL"CHIP"
WATTAGE"1/16W"
BOM_COST"MEM"
CDS_LIB"pure_quanta";
"B"
$PN"2"116;
"A"
$PN"1"107;
%"Q_RES"
"1","(-6425,6125)","0","pure_quanta","I739";
;
LOCATION"R205"
$SEC"1"
CDS_SEC"1"
VALUE"0"
ROOM"RST_CPU0_PLD_TO_DIMM"
PACK_TYPE"0402LF"
PART_NUMBER"CS00002JB38"
TOLERANCE"5%"
MATERIAL"CHIP"
WATTAGE"1/16W"
BOM_COST"MEM"
CDS_LIB"pure_quanta";
"B"
$PN"2"98;
"A"
$PN"1"108;
%"Q_RES"
"1","(-6425,6175)","0","pure_quanta","I740";
;
LOCATION"R204"
$SEC"1"
CDS_SEC"1"
VALUE"0"
ROOM"RST_CPU0_PLD_TO_DIMM"
PACK_TYPE"0402LF"
PART_NUMBER"CS00002JB38"
TOLERANCE"5%"
MATERIAL"CHIP"
WATTAGE"1/16W"
BOM_COST"MEM"
CDS_LIB"pure_quanta";
"B"
$PN"2"97;
"A"
$PN"1"109;
%"Q_RES"
"1","(-6425,5975)","0","pure_quanta","I741";
;
LOCATION"R238"
$SEC"1"
CDS_SEC"1"
VALUE"0"
ROOM"RST_CPU0_PLD_TO_DIMM"
PACK_TYPE"0402LF"
PART_NUMBER"CS00002JB38"
TOLERANCE"5%"
MATERIAL"CHIP"
WATTAGE"1/16W"
CDS_LIB"pure_quanta"
BOM_COST"MEM";
"B"
$PN"2"114;
"A"
$PN"1"100;
%"Q_RES"
"1","(-6425,5925)","0","pure_quanta","I742";
;
LOCATION"R244"
$SEC"1"
CDS_SEC"1"
VALUE"0"
ROOM"RST_CPU0_PLD_TO_DIMM"
PACK_TYPE"0402LF"
PART_NUMBER"CS00002JB38"
TOLERANCE"5%"
MATERIAL"CHIP"
WATTAGE"1/16W"
BOM_COST"MEM"
CDS_LIB"pure_quanta";
"B"
$PN"2"113;
"A"
$PN"1"99;
%"Q_RES"
"1","(-6425,5875)","0","pure_quanta","I743";
;
LOCATION"R235"
$SEC"1"
CDS_SEC"1"
VALUE"0"
ROOM"RST_CPU0_PLD_TO_DIMM"
PACK_TYPE"0402LF"
PART_NUMBER"CS00002JB38"
TOLERANCE"5%"
MATERIAL"CHIP"
WATTAGE"1/16W"
BOM_COST"MEM"
CDS_LIB"pure_quanta";
"B"
$PN"2"118;
"A"
$PN"1"91;
%"Q_RES"
"1","(-6425,5825)","0","pure_quanta","I744";
;
LOCATION"R187"
$SEC"1"
CDS_SEC"1"
VALUE"0"
ROOM"RST_CPU0_PLD_TO_DIMM"
PACK_TYPE"0402LF"
PART_NUMBER"CS00002JB38"
TOLERANCE"5%"
MATERIAL"CHIP"
WATTAGE"1/16W"
CDS_LIB"pure_quanta"
BOM_COST"MEM";
"B"
$PN"2"117;
"A"
$PN"1"87;
%"Q_RES"
"1","(-6425,5725)","0","pure_quanta","I745";
;
LOCATION"R236"
$SEC"1"
CDS_SEC"1"
VALUE"0"
ROOM"RST_CPU0_PLD_TO_DIMM"
PACK_TYPE"0402LF"
PART_NUMBER"CS00002JB38"
TOLERANCE"5%"
MATERIAL"CHIP"
WATTAGE"1/16W"
CDS_LIB"pure_quanta"
BOM_COST"MEM";
"B"
$PN"2"120;
"A"
$PN"1"111;
%"Q_RES"
"1","(-6425,5775)","0","pure_quanta","I746";
;
LOCATION"R237"
$SEC"1"
CDS_SEC"1"
VALUE"0"
ROOM"RST_CPU0_PLD_TO_DIMM"
PACK_TYPE"0402LF"
PART_NUMBER"CS00002JB38"
TOLERANCE"5%"
MATERIAL"CHIP"
WATTAGE"1/16W"
CDS_LIB"pure_quanta"
BOM_COST"MEM";
"B"
$PN"2"119;
"A"
$PN"1"56;
%"Q_RES"
"1","(-6425,5675)","0","pure_quanta","I747";
;
LOCATION"R245"
$SEC"1"
CDS_SEC"1"
VALUE"0"
ROOM"RST_CPU0_PLD_TO_DIMM"
PACK_TYPE"0402LF"
PART_NUMBER"CS00002JB38"
TOLERANCE"5%"
MATERIAL"CHIP"
WATTAGE"1/16W"
BOM_COST"MEM"
CDS_LIB"pure_quanta";
"B"
$PN"2"121;
"A"
$PN"1"112;
%"Q_RES"
"1","(-6425,5625)","0","pure_quanta","I748";
;
LOCATION"R246"
$SEC"1"
CDS_SEC"1"
VALUE"0"
ROOM"RST_CPU0_PLD_TO_DIMM"
PACK_TYPE"0402LF"
PART_NUMBER"CS00002JB38"
TOLERANCE"5%"
MATERIAL"CHIP"
WATTAGE"1/16W"
CDS_LIB"pure_quanta"
BOM_COST"MEM";
"B"
$PN"2"66;
"A"
$PN"1"57;
%"Q_RES"
"1","(-6425,5575)","0","pure_quanta","I749";
;
LOCATION"R243"
$SEC"1"
CDS_SEC"1"
VALUE"0"
ROOM"RST_CPU0_PLD_TO_DIMM"
PACK_TYPE"0402LF"
PART_NUMBER"CS00002JB38"
TOLERANCE"5%"
MATERIAL"CHIP"
WATTAGE"1/16W"
CDS_LIB"pure_quanta"
BOM_COST"MEM";
"B"
$PN"2"101;
"A"
$PN"1"88;
%"Q_RES"
"1","(-6425,5425)","0","pure_quanta","I750";
;
LOCATION"R188"
$SEC"1"
CDS_SEC"1"
VALUE"0"
ROOM"RST_CPU0_PLD_TO_DIMM"
PACK_TYPE"0402LF"
PART_NUMBER"CS00002JB38"
TOLERANCE"5%"
MATERIAL"CHIP"
WATTAGE"1/16W"
BOM_COST"MEM"
CDS_LIB"pure_quanta";
"B"
$PN"2"93;
"A"
$PN"1"89;
%"Q_RES"
"1","(-6425,5525)","0","pure_quanta","I751";
;
LOCATION"R190"
$SEC"1"
CDS_SEC"1"
VALUE"0"
ROOM"RST_CPU0_PLD_TO_DIMM"
PACK_TYPE"0402LF"
PART_NUMBER"CS00002JB38"
TOLERANCE"5%"
MATERIAL"CHIP"
WATTAGE"1/16W"
BOM_COST"MEM"
CDS_LIB"pure_quanta";
"B"
$PN"2"106;
"A"
$PN"1"86;
%"Q_RES"
"1","(-6425,5475)","0","pure_quanta","I752";
;
LOCATION"R239"
$SEC"1"
CDS_SEC"1"
VALUE"0"
ROOM"RST_CPU0_PLD_TO_DIMM"
PACK_TYPE"0402LF"
PART_NUMBER"CS00002JB38"
TOLERANCE"5%"
MATERIAL"CHIP"
WATTAGE"1/16W"
BOM_COST"MEM"
CDS_LIB"pure_quanta";
"B"
$PN"2"92;
"A"
$PN"1"58;
%"Q_RES"
"1","(-6425,5325)","0","pure_quanta","I753";
;
LOCATION"R231"
$SEC"1"
CDS_SEC"1"
VALUE"0"
ROOM"RST_CPU0_PLD_TO_DIMM"
PACK_TYPE"0402LF"
PART_NUMBER"CS00002JB38"
TOLERANCE"5%"
MATERIAL"CHIP"
WATTAGE"1/16W"
BOM_COST"MEM"
CDS_LIB"pure_quanta";
"B"
$PN"2"102;
"A"
$PN"1"60;
%"Q_RES"
"1","(-6425,5375)","0","pure_quanta","I754";
;
LOCATION"R189"
$SEC"1"
CDS_SEC"1"
VALUE"0"
ROOM"RST_CPU0_PLD_TO_DIMM"
PACK_TYPE"0402LF"
PART_NUMBER"CS00002JB38"
TOLERANCE"5%"
MATERIAL"CHIP"
WATTAGE"1/16W"
BOM_COST"MEM"
CDS_LIB"pure_quanta";
"B"
$PN"2"105;
"A"
$PN"1"59;
%"Q_RES"
"1","(-6425,5275)","0","pure_quanta","I755";
;
LOCATION"R137"
$SEC"1"
CDS_SEC"1"
VALUE"0"
ROOM"RST_CPU0_PLD_TO_DIMM"
PACK_TYPE"0402LF"
PART_NUMBER"CS00002JB38"
TOLERANCE"5%"
MATERIAL"CHIP"
WATTAGE"1/16W"
CDS_LIB"pure_quanta"
BOM_COST"MEM";
"B"
$PN"2"104;
"A"
$PN"1"70;
%"Q_RES"
"1","(-6425,5225)","0","pure_quanta","I756";
;
LOCATION"R141"
$SEC"1"
CDS_SEC"1"
VALUE"0"
ROOM"RST_CPU0_PLD_TO_DIMM"
PACK_TYPE"0402LF"
PART_NUMBER"CS00002JB38"
TOLERANCE"5%"
MATERIAL"CHIP"
WATTAGE"1/16W"
BOM_COST"MEM"
CDS_LIB"pure_quanta";
"B"
$PN"2"103;
"A"
$PN"1"61;
%"Q_RES"
"1","(-6425,5025)","0","pure_quanta","I758";
;
LOCATION"R269"
$SEC"1"
CDS_SEC"1"
VALUE"0"
ROOM"RST_CPU0_PLD_TO_DIMM"
PACK_TYPE"0402LF"
PART_NUMBER"CS00002JB38"
TOLERANCE"5%"
MATERIAL"CHIP"
WATTAGE"1/16W"
BOM_COST"MEM"
CDS_LIB"pure_quanta";
"B"
$PN"2"95;
"A"
$PN"1"90;
%"Q_RES"
"1","(-6425,4925)","0","pure_quanta","I759";
;
LOCATION"R233"
$SEC"1"
CDS_SEC"1"
VALUE"0"
ROOM"RST_CPU0_PLD_TO_DIMM"
PACK_TYPE"0402LF"
PART_NUMBER"CS00002JB38"
TOLERANCE"5%"
MATERIAL"CHIP"
WATTAGE"1/16W"
CDS_LIB"pure_quanta"
BOM_COST"MEM";
"B"
$PN"2"94;
"A"
$PN"1"19;
%"Q_RES"
"1","(-6425,4975)","0","pure_quanta","I760";
;
LOCATION"R268"
$SEC"1"
CDS_SEC"1"
VALUE"0"
ROOM"RST_CPU0_PLD_TO_DIMM"
PACK_TYPE"0402LF"
PART_NUMBER"CS00002JB38"
TOLERANCE"5%"
MATERIAL"CHIP"
WATTAGE"1/16W"
CDS_LIB"pure_quanta"
BOM_COST"MEM";
"B"
$PN"2"83;
"A"
$PN"1"85;
%"Q_RES"
"1","(-6425,4825)","0","pure_quanta","I784";
;
LOCATION"R222"
$SEC"1"
CDS_SEC"1"
VALUE"0"
ROOM"RST_CPU0_PLD_TO_DIMM"
PACK_TYPE"0402LF"
PART_NUMBER"CS00002JB38"
TOLERANCE"5%"
MATERIAL"CHIP"
WATTAGE"1/16W"
CDS_LIB"pure_quanta"
BOM_COST"MEM";
"B"
$PN"2"84;
"A"
$PN"1"18;
%"Q_RES"
"1","(-6425,4775)","0","pure_quanta","I785";
;
LOCATION"R264"
$SEC"1"
CDS_SEC"1"
VALUE"0"
ROOM"RST_CPU0_PLD_TO_DIMM"
PACK_TYPE"0402LF"
PART_NUMBER"CS00002JB38"
TOLERANCE"5%"
MATERIAL"CHIP"
WATTAGE"1/16W"
BOM_COST"MEM"
CDS_LIB"pure_quanta";
"B"
$PN"2"82;
"A"
$PN"1"24;
%"Q_RES"
"1","(-6425,4725)","0","pure_quanta","I786";
;
LOCATION"R232"
$SEC"1"
CDS_SEC"1"
VALUE"33"
ROOM"RST_CPU0_PLD_TO_DIMM"
PACK_TYPE"0402LF"
PART_NUMBER"CS03302JB29"
TOLERANCE"5%"
MATERIAL"CHIP"
WATTAGE"1/16W"
BOM_COST"MEM"
CDS_LIB"pure_quanta";
"B"
$PN"2"21;
"A"
$PN"1"17;
%"Q_RES"
"1","(-6425,4625)","0","pure_quanta","I788";
;
LOCATION"R261"
$SEC"1"
CDS_SEC"1"
VALUE"0"
ROOM"RST_CPU0_PLD_TO_DIMM"
PACK_TYPE"0402LF"
PART_NUMBER"CS00002JB38"
TOLERANCE"5%"
MATERIAL"CHIP"
WATTAGE"1/16W"
BOM_COST"MEM"
CDS_LIB"pure_quanta";
"B"
$PN"2"22;
"A"
$PN"1"10;
%"Q_RES"
"1","(-6425,4575)","0","pure_quanta","I789";
;
LOCATION"R260"
$SEC"1"
CDS_SEC"1"
VALUE"0"
ROOM"RST_CPU0_PLD_TO_DIMM"
PACK_TYPE"0402LF"
PART_NUMBER"CS00002JB38"
TOLERANCE"5%"
MATERIAL"CHIP"
WATTAGE"1/16W"
BOM_COST"MEM"
CDS_LIB"pure_quanta";
"B"
$PN"2"23;
"A"
$PN"1"11;
%"Q_RES"
"1","(-6425,4425)","0","pure_quanta","I790";
;
LOCATION"R263"
$SEC"1"
CDS_SEC"1"
VALUE"0"
ROOM"RST_CPU0_PLD_TO_DIMM"
PACK_TYPE"0402LF"
PART_NUMBER"CS00002JB38"
TOLERANCE"5%"
MATERIAL"CHIP"
WATTAGE"1/16W"
CDS_LIB"pure_quanta"
BOM_COST"MEM";
"B"
$PN"2"15;
"A"
$PN"1"13;
%"Q_RES"
"1","(-6425,4375)","0","pure_quanta","I791";
;
LOCATION"R184"
$SEC"1"
CDS_SEC"1"
VALUE"0"
ROOM"RST_CPU0_PLD_TO_DIMM"
PACK_TYPE"0402LF"
PART_NUMBER"CS00002JB38"
TOLERANCE"5%"
MATERIAL"CHIP"
WATTAGE"1/16W"
BOM_COST"MEM"
CDS_LIB"pure_quanta";
"B"
$PN"2"14;
"A"
$PN"1"1;
%"Q_RES"
"1","(-6425,4275)","0","pure_quanta","I792";
;
LOCATION"R181"
$SEC"1"
CDS_SEC"1"
VALUE"0"
ROOM"RST_CPU0_PLD_TO_DIMM"
PACK_TYPE"0402LF"
PART_NUMBER"CS00002JB38"
TOLERANCE"5%"
MATERIAL"CHIP"
WATTAGE"1/16W"
BOM_COST"MEM"
CDS_LIB"pure_quanta";
"B"
$PN"2"3;
"A"
$PN"1"25;
%"Q_RES"
"1","(-6425,4175)","0","pure_quanta","I793";
;
LOCATION"R262"
$SEC"1"
CDS_SEC"1"
VALUE"0"
ROOM"RST_CPU0_PLD_TO_DIMM"
PACK_TYPE"0402LF"
PART_NUMBER"CS00002JB38"
TOLERANCE"5%"
MATERIAL"CHIP"
WATTAGE"1/16W"
BOM_COST"MEM"
CDS_LIB"pure_quanta";
"B"
$PN"2"5;
"A"
$PN"1"69;
%"Q_RES"
"1","(-6425,4225)","0","pure_quanta","I794";
;
LOCATION"R180"
$SEC"1"
CDS_SEC"1"
VALUE"0"
ROOM"RST_CPU0_PLD_TO_DIMM"
PACK_TYPE"0402LF"
PART_NUMBER"CS00002JB38"
TOLERANCE"5%"
MATERIAL"CHIP"
WATTAGE"1/16W"
BOM_COST"MEM"
CDS_LIB"pure_quanta";
"B"
$PN"2"4;
"A"
$PN"1"68;
%"Q_RES"
"1","(-6425,4025)","0","pure_quanta","I795";
;
LOCATION"R1179"
$SEC"1"
CDS_SEC"1"
VALUE"0"
ROOM"RST_CPU0_PLD_TO_DIMM"
PACK_TYPE"0402LF"
PART_NUMBER"CS00002JB38"
TOLERANCE"5%"
MATERIAL"CHIP"
WATTAGE"1/16W"
BOM_COST"MEM"
CDS_LIB"pure_quanta";
"B"
$PN"2"7;
"A"
$PN"1"73;
%"GND"
"1","(-6175,300)","0","pure_quanta_power","I833";
;
HDL_POWER"GND"
CDS_LIB"pure_quanta_power"
SIZE"1B";
"A<SIZE-1..0>\NAC"125;
%"LCMXO3D9400HC5BG484C"
"6","(-6775,1650)","0","pure_quanta","I834";
;
LOCATION"U18"
$SEC"6"
CDS_SEC"6"
PART_NUMBER"AJ094000T05"
VALUE"LCMXO3D-9400HC-5BG484C"
MATERIAL"IC"
PART_TYPE"SMLF"
NEEDS_NO_SIZE"TRUE"
CDS_LMAN_SYM_OUTLINE"-250,1350,250,-1350"
CDS_LIB"pure_quanta";
"GND_AB22"
$PN"AB22"125;
"GND_AB1"
$PN"AB1"125;
"GND_Y7"
$PN"Y7"125;
"GND_Y16"
$PN"Y16"125;
"GND_W12"
$PN"W12"125;
"GND_V21"
$PN"V21"125;
"GND_V2"
$PN"V2"125;
"GND_R15"
$PN"R15"125;
"GND_R8"
$PN"R8"125;
"GND_P14"
$PN"P14"125;
"GND_P13"
$PN"P13"125;
"GND_P12"
$PN"P12"125;
"GND_P11"
$PN"P11"125;
"GND_P10"
$PN"P10"125;
"GND_P9"
$PN"P9"125;
"GND_N21"
$PN"N21"125;
"GND_N14"
$PN"N14"125;
"GND_N9"
$PN"N9"125;
"GND_M14"
$PN"M14"125;
"GND_M13"
$PN"M13"125;
"GND_M10"
$PN"M10"125;
"GND_M9"
$PN"M9"125;
"GND_M4"
$PN"M4"125;
"GND_L18"
$PN"L18"125;
"GND_L14"
$PN"L14"125;
"GND_L13"
$PN"L13"125;
"GND_L10"
$PN"L10"125;
"GND_L9"
$PN"L9"125;
"GND_L2"
$PN"L2"125;
"GND_K21"
$PN"K21"125;
"GND_K14"
$PN"K14"125;
"GND_K9"
$PN"K9"125;
"GND_J14"
$PN"J14"125;
"GND_J13"
$PN"J13"125;
"GND_J12"
$PN"J12"125;
"GND_J11"
$PN"J11"125;
"GND_J10"
$PN"J10"125;
"GND_J9"
$PN"J9"125;
"GND_H15"
$PN"H15"125;
"GND_H13"
$PN"H13"125;
"GND_H10"
$PN"H10"125;
"GND_H8"
$PN"H8"125;
"GND_F21"
$PN"F21"125;
"GND_F2"
$PN"F2"125;
"GND_E18"
$PN"E18"125;
"GND_E5"
$PN"E5"125;
"GND_C11"
$PN"C11"125;
"GND_C2"
$PN"C2"125;
"GND_B16"
$PN"B16"125;
"GND_B7"
$PN"B7"125;
"GND_A22"
$PN"A22"125;
"GND_A1"
$PN"A1"125;
%"Q_RES"
"1","(-3225,5875)","0","pure_quanta","I838";
;
LOCATION"R266"
$SEC"1"
CDS_SEC"1"
VALUE"33"
CDS_LIB"pure_quanta"
BOM_COST"MEM"
WATTAGE"1/16W"
MATERIAL"CHIP"
TOLERANCE"5%"
PART_NUMBER"CS03302JB29"
PACK_TYPE"0402LF"
ROOM"RST_CPU0_PLD_TO_DIMM";
"B"
$PN"2"138;
"A"
$PN"1"133;
%"Q_RES"
"1","(-3225,5775)","0","pure_quanta","I840";
;
LOCATION"R220"
$SEC"1"
CDS_SEC"1"
VALUE"33"
CDS_LIB"pure_quanta"
ROOM"RST_CPU0_PLD_TO_DIMM"
PACK_TYPE"0402LF"
PART_NUMBER"CS03302JB29"
TOLERANCE"5%"
MATERIAL"CHIP"
WATTAGE"1/16W"
BOM_COST"MEM";
"B"
$PN"2"140;
"A"
$PN"1"122;
%"Q_RES"
"1","(-3225,5575)","0","pure_quanta","I842";
;
LOCATION"R221"
$SEC"1"
CDS_SEC"1"
VALUE"33"
CDS_LIB"pure_quanta"
ROOM"RST_CPU0_PLD_TO_DIMM"
PACK_TYPE"0402LF"
PART_NUMBER"CS03302JB29"
TOLERANCE"5%"
MATERIAL"CHIP"
WATTAGE"1/16W"
BOM_COST"MEM";
"B"
$PN"2"123;
"A"
$PN"1"131;
%"Q_RES"
"1","(-6425,6025)","0","pure_quanta","I844";
;
LOCATION"R267"
$SEC"1"
CDS_SEC"1"
VALUE"33"
CDS_LIB"pure_quanta"
ROOM"RST_CPU0_PLD_TO_DIMM"
PACK_TYPE"0402LF"
PART_NUMBER"CS03302JB29"
TOLERANCE"5%"
MATERIAL"CHIP"
WATTAGE"1/16W"
BOM_COST"MEM";
"B"
$PN"2"115;
"A"
$PN"1"110;
END.
